(kicad_pcb
	(version 20260206)
	(generator "pcbnew")
	(generator_version "10.0")
	(general
		(thickness 1.6)
		(legacy_teardrops no)
	)
	(paper "A4")
	(title_block
		(title "04192023_DAF0TMB3IC0_F0TG_MB_C_brd_V02_OCP.brd")
		(comment 1 "Grand Teton / footprints 7922-7929 of 8354")
	)
	(layers
		(0 "F.Cu" signal "TOP")
		(4 "In1.Cu" signal "GND")
		(6 "In2.Cu" signal "IN1")
		(8 "In3.Cu" signal "GND1")
		(10 "In4.Cu" signal "IN2")
		(12 "In5.Cu" signal "GND2")
		(14 "In6.Cu" signal "IN3")
		(16 "In7.Cu" signal "GND3")
		(18 "In8.Cu" signal "VCC")
		(20 "In9.Cu" signal "VCC1")
		(22 "In10.Cu" signal "GND4")
		(24 "In11.Cu" signal "IN4")
		(26 "In12.Cu" signal "GND5")
		(28 "In13.Cu" signal "IN5")
		(30 "In14.Cu" signal "GND6")
		(32 "In15.Cu" signal "IN6")
		(34 "In16.Cu" signal "GND7")
		(2 "B.Cu" signal "BOTTOM")
		(9 "F.Adhes" user "F.Adhesive")
		(11 "B.Adhes" user "B.Adhesive")
		(13 "F.Paste" user "Package Geometry/Pastemask Top")
		(15 "B.Paste" user "Package Geometry/Pastemask Bottom")
		(5 "F.SilkS" user "Ref Des/Silkscreen Top")
		(7 "B.SilkS" user "Ref Des/Silkscreen Bottom")
		(1 "F.Mask" user "Board Geometry/Soldermask Top")
		(3 "B.Mask" user "Board Geometry/Soldermask Bottom")
		(17 "Dwgs.User" user "User.Drawings")
		(19 "Cmts.User" user "User.Comments")
		(21 "Eco1.User" user "User.Eco1")
		(23 "Eco2.User" user "User.Eco2")
		(25 "Edge.Cuts" user "Board Geometry/Outline")
		(27 "Margin" user)
		(31 "F.CrtYd" user "Package Geometry/Place Bound Top")
		(29 "B.CrtYd" user "Package Geometry/Place Bound Bottom")
		(35 "F.Fab" user "Ref Des/Assembly Top")
		(33 "B.Fab" user "Ref Des/Assembly Bottom")
	)
	(footprint ""
		(layer "B.Cu")
		(at 444.617602 -418.58311 90)
		(property "Reference" "PR6610"
			(at 0 0 90)
			(layer "B.SilkS")
			(hide yes)
			(effects
				(font
					(size 1.27 1.27)
				)
				(justify mirror)
			)
		)
		(property "Value" ""
			(at 0 0 90)
			(layer "B.Fab")
			(effects
				(font
					(size 1.27 1.27)
				)
				(justify mirror)
			)
		)
		(duplicate_pad_numbers_are_jumpers no)
		(fp_line
			(start 0.7874 -0.4064)
			(end -0.7874 -0.4064)
			(stroke
				(width 0.1524)
				(type default)
			)
			(layer "B.SilkS")
		)
		(fp_line
			(start -0.7874 -0.4064)
			(end -0.7874 0.4064)
			(stroke
				(width 0.1524)
				(type default)
			)
			(layer "B.SilkS")
		)
		(fp_line
			(start 0.7874 0.4064)
			(end 0.7874 -0.4064)
			(stroke
				(width 0.1524)
				(type default)
			)
			(layer "B.SilkS")
		)
		(fp_line
			(start -0.7874 0.4064)
			(end 0.7874 0.4064)
			(stroke
				(width 0.1524)
				(type default)
			)
			(layer "B.SilkS")
		)
		(fp_line
			(start 0.67945 -0.305054)
			(end 0.12065 -0.305054)
			(stroke
				(width 0.1)
				(type default)
			)
			(layer "B.Fab")
		)
		(fp_line
			(start 0.12065 -0.305054)
			(end 0.12065 -0.2794)
			(stroke
				(width 0.1)
				(type default)
			)
			(layer "B.Fab")
		)
		(fp_line
			(start -0.12065 -0.3048)
			(end -0.67945 -0.3048)
			(stroke
				(width 0.1)
				(type default)
			)
			(layer "B.Fab")
		)
		(fp_line
			(start -0.67945 -0.3048)
			(end -0.67945 0.3048)
			(stroke
				(width 0.1)
				(type default)
			)
			(layer "B.Fab")
		)
		(fp_line
			(start 0.12065 -0.2794)
			(end -0.12065 -0.2794)
			(stroke
				(width 0.1)
				(type default)
			)
			(layer "B.Fab")
		)
		(fp_line
			(start -0.12065 -0.2794)
			(end -0.12065 -0.3048)
			(stroke
				(width 0.1)
				(type default)
			)
			(layer "B.Fab")
		)
		(fp_line
			(start 0.12065 0.2794)
			(end 0.12065 0.3048)
			(stroke
				(width 0.1)
				(type default)
			)
			(layer "B.Fab")
		)
		(fp_line
			(start -0.120396 0.2794)
			(end 0.12065 0.2794)
			(stroke
				(width 0.1)
				(type default)
			)
			(layer "B.Fab")
		)
		(fp_line
			(start 0.67945 0.3048)
			(end 0.67945 -0.305054)
			(stroke
				(width 0.1)
				(type default)
			)
			(layer "B.Fab")
		)
		(fp_line
			(start 0.12065 0.3048)
			(end 0.67945 0.3048)
			(stroke
				(width 0.1)
				(type default)
			)
			(layer "B.Fab")
		)
		(fp_line
			(start -0.120396 0.3048)
			(end -0.120396 0.2794)
			(stroke
				(width 0.1)
				(type default)
			)
			(layer "B.Fab")
		)
		(fp_line
			(start -0.67945 0.3048)
			(end -0.120396 0.3048)
			(stroke
				(width 0.1)
				(type default)
			)
			(layer "B.Fab")
		)
		(pad "1" smd circle
			(at 0.40005 0 270)
			(size 0 0)
			(layers "B.Cu" "B.Mask" "B.Paste")
			(net "NC_P0V9_RETIMER_CPU0_IMON4")
		)
		(pad "2" smd circle
			(at -0.40005 0 270)
			(size 0 0)
			(layers "B.Cu" "B.Mask" "B.Paste")
			(net "GND")
		)
	)
	(footprint ""
		(layer "B.Cu")
		(at 462.124552 -380.027434 90)
		(property "Reference" "PC534"
			(at -6.293104 1.933448 0)
			(unlocked yes)
			(layer "B.SilkS")
			(effects
				(font
					(size 0.7874 0.5842)
					(thickness 0.1524)
				)
				(justify left mirror)
			)
		)
		(property "Value" ""
			(at 0 0 90)
			(layer "B.Fab")
			(effects
				(font
					(size 1.27 1.27)
				)
				(justify mirror)
			)
		)
		(duplicate_pad_numbers_are_jumpers no)
		(fp_line
			(start 4.84378 -2.150618)
			(end 4.53898 -2.150618)
			(stroke
				(width 0.1524)
				(type default)
			)
			(layer "B.SilkS")
		)
		(fp_line
			(start 4.84378 -2.150618)
			(end 4.842256 2.163064)
			(stroke
				(width 0.1524)
				(type default)
			)
			(layer "B.SilkS")
		)
		(fp_line
			(start 4.69138 -2.150618)
			(end 4.692396 2.161032)
			(stroke
				(width 0.1524)
				(type default)
			)
			(layer "B.SilkS")
		)
		(fp_line
			(start 4.53898 -2.150618)
			(end 4.539742 2.152142)
			(stroke
				(width 0.1524)
				(type default)
			)
			(layer "B.SilkS")
		)
		(fp_line
			(start 4.53898 -2.15011)
			(end -4.53898 -2.15011)
			(stroke
				(width 0.1524)
				(type default)
			)
			(layer "B.SilkS")
		)
		(fp_line
			(start -4.53898 -2.15011)
			(end -4.53898 1.882648)
			(stroke
				(width 0.1524)
				(type default)
			)
			(layer "B.SilkS")
		)
		(fp_line
			(start 4.53898 2.15011)
			(end 4.53898 -2.15011)
			(stroke
				(width 0.1524)
				(type default)
			)
			(layer "B.SilkS")
		)
		(fp_line
			(start -4.056634 2.15011)
			(end 4.53898 2.15011)
			(stroke
				(width 0.1524)
				(type default)
			)
			(layer "B.SilkS")
		)
		(fp_line
			(start 4.83108 2.150364)
			(end 4.447794 2.149348)
			(stroke
				(width 0.1524)
				(type default)
			)
			(layer "B.SilkS")
		)
		(fp_line
			(start 3.64998 -2.15011)
			(end -3.64998 -2.15011)
			(stroke
				(width 0.1)
				(type default)
			)
			(layer "B.Fab")
		)
		(fp_line
			(start -3.64998 -2.15011)
			(end -3.64998 2.15011)
			(stroke
				(width 0.1)
				(type default)
			)
			(layer "B.Fab")
		)
		(fp_line
			(start 3.64998 2.15011)
			(end 3.64998 -2.15011)
			(stroke
				(width 0.1)
				(type default)
			)
			(layer "B.Fab")
		)
		(fp_line
			(start -3.64998 2.15011)
			(end 3.64998 2.15011)
			(stroke
				(width 0.1)
				(type default)
			)
			(layer "B.Fab")
		)
		(fp_text user "+"
			(at 6.214872 -0.337058 90)
			(unlocked yes)
			(layer "B.SilkS")
			(effects
				(font
					(size 1.905 1.4224)
					(thickness 0.1524)
				)
				(justify left mirror)
			)
		)
		(fp_text user "-"
			(at -4.313174 -0.094488 90)
			(unlocked yes)
			(layer "B.SilkS")
			(effects
				(font
					(size 1.905 1.4224)
					(thickness 0.1524)
				)
				(justify left mirror)
			)
		)
		(fp_text user "+"
			(at 6.214872 -0.337058 90)
			(unlocked yes)
			(layer "B.Fab")
			(effects
				(font
					(size 1.905 1.4224)
					(thickness 0.1524)
				)
				(justify left mirror)
			)
		)
		(fp_text user "-"
			(at -4.313174 -0.094488 90)
			(unlocked yes)
			(layer "B.Fab")
			(effects
				(font
					(size 1.905 1.4224)
					(thickness 0.1524)
				)
				(justify left mirror)
			)
		)
		(pad "1" smd rect
			(at 3.199892 0 270)
			(size 2.413 2.8194)
			(layers "B.Cu" "B.Mask" "B.Paste")
			(net "P0V9_CPU0_RT_2D")
		)
		(pad "2" smd rect
			(at -3.199892 0 270)
			(size 2.413 2.8194)
			(layers "B.Cu" "B.Mask" "B.Paste")
			(net "GND")
		)
	)
	(footprint ""
		(layer "B.Cu")
		(at 474.16466 -297.49877 180)
		(property "Reference" "DB6"
			(at 2.845308 -7.762748 270)
			(unlocked yes)
			(layer "B.SilkS")
			(effects
				(font
					(size 0.7874 0.5842)
					(thickness 0.1524)
				)
				(justify left mirror)
			)
		)
		(property "Value" ""
			(at 0 0 0)
			(layer "B.Fab")
			(effects
				(font
					(size 1.27 1.27)
				)
				(justify mirror)
			)
		)
		(duplicate_pad_numbers_are_jumpers no)
		(fp_line
			(start 3.330702 -4.771136)
			(end -3.330702 -4.771136)
			(stroke
				(width 0.1524)
				(type default)
			)
			(layer "B.SilkS")
		)
		(fp_line
			(start 0 4.011168)
			(end 3.330702 -4.771136)
			(stroke
				(width 0.1524)
				(type default)
			)
			(layer "B.SilkS")
		)
		(fp_line
			(start -3.330702 -4.771136)
			(end 0 4.011168)
			(stroke
				(width 0.1524)
				(type default)
			)
			(layer "B.SilkS")
		)
		(fp_line
			(start 3.330702 -4.771136)
			(end -3.330702 -4.771136)
			(stroke
				(width 0.1)
				(type default)
			)
			(layer "B.Fab")
		)
		(fp_line
			(start 0 4.011168)
			(end 3.330702 -4.771136)
			(stroke
				(width 0.1)
				(type default)
			)
			(layer "B.Fab")
		)
		(fp_line
			(start -3.330702 -4.771136)
			(end 0 4.011168)
			(stroke
				(width 0.1)
				(type default)
			)
			(layer "B.Fab")
		)
		(pad "1" thru_hole circle
			(at 0 0)
			(size 2.159 2.159)
			(drill 1.7018)
			(layers "*.Cu" "*.Mask")
			(remove_unused_layers no)
			(net "T1_GND")
			(clearance 0.0254)
			(thermal_gap 0.0254)
		)
		(pad "2" thru_hole circle
			(at 1.27 -3.348736)
			(size 2.159 2.159)
			(drill 1.7018)
			(layers "*.Cu" "*.Mask")
			(remove_unused_layers no)
			(net "TDR_SE_45_OHM_BOT")
			(clearance 0.0254)
			(thermal_gap 0.0254)
		)
		(pad "3" thru_hole circle
			(at -1.27 -3.348736)
			(size 2.159 2.159)
			(drill 1.7018)
			(layers "*.Cu" "*.Mask")
			(remove_unused_layers no)
			(net "TDR_SE_45_OHM_BOT")
			(clearance 0.0254)
			(thermal_gap 0.0254)
		)
	)
	(footprint ""
		(layer "B.Cu")
		(at 163.46932 -413.5374 90)
		(property "Reference" "R691"
			(at 0 0 90)
			(layer "B.SilkS")
			(hide yes)
			(effects
				(font
					(size 1.27 1.27)
				)
				(justify mirror)
			)
		)
		(property "Value" ""
			(at 0 0 90)
			(layer "B.Fab")
			(effects
				(font
					(size 1.27 1.27)
				)
				(justify mirror)
			)
		)
		(duplicate_pad_numbers_are_jumpers no)
		(fp_line
			(start 0.32512 -0.175006)
			(end -0.32512 -0.175006)
			(stroke
				(width 0.1)
				(type default)
			)
			(layer "B.Fab")
		)
		(fp_line
			(start -0.32512 -0.175006)
			(end -0.32512 0.175006)
			(stroke
				(width 0.1)
				(type default)
			)
			(layer "B.Fab")
		)
		(fp_line
			(start 0.32512 0.175006)
			(end 0.32512 -0.175006)
			(stroke
				(width 0.1)
				(type default)
			)
			(layer "B.Fab")
		)
		(fp_line
			(start -0.32512 0.175006)
			(end 0.32512 0.175006)
			(stroke
				(width 0.1)
				(type default)
			)
			(layer "B.Fab")
		)
		(pad "1" smd rect
			(at 0.2667 0 270)
			(size 0.3048 0.381)
			(layers "B.Cu" "B.Mask" "B.Paste")
			(net "SMB_RT_CPU1_P2_ROM_MUX_1D_SCL")
		)
		(pad "2" smd rect
			(at -0.2667 0 90)
			(size 0.3048 0.381)
			(layers "B.Cu" "B.Mask" "B.Paste")
			(net "SMB_RT_CPU1_P2_ROM_MUX_1D_R_SCL")
		)
	)
	(footprint ""
		(layer "B.Cu")
		(at 320.318384 -396.393162 -90)
		(property "Reference" "C541"
			(at 0 0 90)
			(layer "B.SilkS")
			(hide yes)
			(effects
				(font
					(size 1.27 1.27)
				)
				(justify mirror)
			)
		)
		(property "Value" ""
			(at 0 0 90)
			(layer "B.Fab")
			(effects
				(font
					(size 1.27 1.27)
				)
				(justify mirror)
			)
		)
		(duplicate_pad_numbers_are_jumpers no)
		(fp_line
			(start -0.299974 0.150114)
			(end 0.299974 0.150114)
			(stroke
				(width 0.1)
				(type default)
			)
			(layer "B.Fab")
		)
		(fp_line
			(start 0.299974 0.150114)
			(end 0.299974 -0.150114)
			(stroke
				(width 0.1)
				(type default)
			)
			(layer "B.Fab")
		)
		(fp_line
			(start -0.299974 -0.150114)
			(end -0.299974 0.150114)
			(stroke
				(width 0.1)
				(type default)
			)
			(layer "B.Fab")
		)
		(fp_line
			(start 0.299974 -0.150114)
			(end -0.299974 -0.150114)
			(stroke
				(width 0.1)
				(type default)
			)
			(layer "B.Fab")
		)
		(pad "1" smd rect
			(at 0.2667 0 90)
			(size 0.3048 0.381)
			(layers "B.Cu" "B.Mask" "B.Paste")
			(net "P0V9_CPU0_RT0_2A")
		)
		(pad "2" smd rect
			(at -0.2667 0 90)
			(size 0.3048 0.381)
			(layers "B.Cu" "B.Mask" "B.Paste")
			(net "GND")
		)
	)
	(footprint ""
		(layer "B.Cu")
		(at 87.106252 -386.766562 90)
		(property "Reference" "C205"
			(at 0 0 90)
			(layer "B.SilkS")
			(hide yes)
			(effects
				(font
					(size 1.27 1.27)
				)
				(justify mirror)
			)
		)
		(property "Value" ""
			(at 0 0 90)
			(layer "B.Fab")
			(effects
				(font
					(size 1.27 1.27)
				)
				(justify mirror)
			)
		)
		(duplicate_pad_numbers_are_jumpers no)
		(fp_line
			(start 0.299974 -0.150114)
			(end -0.299974 -0.150114)
			(stroke
				(width 0.1)
				(type default)
			)
			(layer "B.Fab")
		)
		(fp_line
			(start -0.299974 -0.150114)
			(end -0.299974 0.150114)
			(stroke
				(width 0.1)
				(type default)
			)
			(layer "B.Fab")
		)
		(fp_line
			(start 0.299974 0.150114)
			(end 0.299974 -0.150114)
			(stroke
				(width 0.1)
				(type default)
			)
			(layer "B.Fab")
		)
		(fp_line
			(start -0.299974 0.150114)
			(end 0.299974 0.150114)
			(stroke
				(width 0.1)
				(type default)
			)
			(layer "B.Fab")
		)
		(pad "1" smd rect
			(at 0.2667 0 270)
			(size 0.3048 0.381)
			(layers "B.Cu" "B.Mask" "B.Paste")
			(net "P1V8_CPU1_RT1_1A")
		)
		(pad "2" smd rect
			(at -0.2667 0 270)
			(size 0.3048 0.381)
			(layers "B.Cu" "B.Mask" "B.Paste")
			(net "GND")
		)
	)
	(footprint ""
		(layer "B.Cu")
		(at 105.960164 -261.255256 180)
		(property "Reference" "C2509"
			(at 0 0 0)
			(layer "B.SilkS")
			(hide yes)
			(effects
				(font
					(size 1.27 1.27)
				)
				(justify mirror)
			)
		)
		(property "Value" ""
			(at 0 0 0)
			(layer "B.Fab")
			(effects
				(font
					(size 1.27 1.27)
				)
				(justify mirror)
			)
		)
		(duplicate_pad_numbers_are_jumpers no)
		(fp_line
			(start 0.7874 0.4064)
			(end 0.7874 -0.4064)
			(stroke
				(width 0.1524)
				(type default)
			)
			(layer "B.SilkS")
		)
		(fp_line
			(start 0.7874 -0.4064)
			(end -0.7874 -0.4064)
			(stroke
				(width 0.1524)
				(type default)
			)
			(layer "B.SilkS")
		)
		(fp_line
			(start -0.7874 0.4064)
			(end 0.7874 0.4064)
			(stroke
				(width 0.1524)
				(type default)
			)
			(layer "B.SilkS")
		)
		(fp_line
			(start -0.7874 -0.4064)
			(end -0.7874 0.4064)
			(stroke
				(width 0.1524)
				(type default)
			)
			(layer "B.SilkS")
		)
		(fp_line
			(start 0.67945 0.3048)
			(end 0.67945 -0.305054)
			(stroke
				(width 0.1)
				(type default)
			)
			(layer "B.Fab")
		)
		(fp_line
			(start 0.67945 -0.305054)
			(end 0.12065 -0.305054)
			(stroke
				(width 0.1)
				(type default)
			)
			(layer "B.Fab")
		)
		(fp_line
			(start 0.12065 0.3048)
			(end 0.67945 0.3048)
			(stroke
				(width 0.1)
				(type default)
			)
			(layer "B.Fab")
		)
		(fp_line
			(start 0.12065 0.2794)
			(end 0.12065 0.3048)
			(stroke
				(width 0.1)
				(type default)
			)
			(layer "B.Fab")
		)
		(fp_line
			(start 0.12065 -0.2794)
			(end -0.12065 -0.2794)
			(stroke
				(width 0.1)
				(type default)
			)
			(layer "B.Fab")
		)
		(fp_line
			(start 0.12065 -0.305054)
			(end 0.12065 -0.2794)
			(stroke
				(width 0.1)
				(type default)
			)
			(layer "B.Fab")
		)
		(fp_line
			(start -0.120396 0.3048)
			(end -0.120396 0.2794)
			(stroke
				(width 0.1)
				(type default)
			)
			(layer "B.Fab")
		)
		(fp_line
			(start -0.120396 0.2794)
			(end 0.12065 0.2794)
			(stroke
				(width 0.1)
				(type default)
			)
			(layer "B.Fab")
		)
		(fp_line
			(start -0.12065 -0.2794)
			(end -0.12065 -0.3048)
			(stroke
				(width 0.1)
				(type default)
			)
			(layer "B.Fab")
		)
		(fp_line
			(start -0.12065 -0.3048)
			(end -0.67945 -0.3048)
			(stroke
				(width 0.1)
				(type default)
			)
			(layer "B.Fab")
		)
		(fp_line
			(start -0.67945 0.3048)
			(end -0.120396 0.3048)
			(stroke
				(width 0.1)
				(type default)
			)
			(layer "B.Fab")
		)
		(fp_line
			(start -0.67945 -0.3048)
			(end -0.67945 0.3048)
			(stroke
				(width 0.1)
				(type default)
			)
			(layer "B.Fab")
		)
		(pad "1" smd circle
			(at 0.40005 0)
			(size 0 0)
			(layers "B.Cu" "B.Mask" "B.Paste")
			(net "PVDDIO_P1")
		)
		(pad "2" smd circle
			(at -0.40005 0)
			(size 0 0)
			(layers "B.Cu" "B.Mask" "B.Paste")
			(net "GND")
		)
	)
	(footprint ""
		(layer "B.Cu")
		(at 367.671858 -135.970772)
		(property "Reference" "R6089"
			(at 0 0 0)
			(layer "B.SilkS")
			(hide yes)
			(effects
				(font
					(size 1.27 1.27)
				)
				(justify mirror)
			)
		)
		(property "Value" ""
			(at 0 0 0)
			(layer "B.Fab")
			(effects
				(font
					(size 1.27 1.27)
				)
				(justify mirror)
			)
		)
		(duplicate_pad_numbers_are_jumpers no)
		(fp_line
			(start -0.7874 -0.4064)
			(end -0.7874 0.4064)
			(stroke
				(width 0.1524)
				(type default)
			)
			(layer "B.SilkS")
		)
		(fp_line
			(start -0.7874 0.4064)
			(end 0.7874 0.4064)
			(stroke
				(width 0.1524)
				(type default)
			)
			(layer "B.SilkS")
		)
		(fp_line
			(start 0.7874 -0.4064)
			(end -0.7874 -0.4064)
			(stroke
				(width 0.1524)
				(type default)
			)
			(layer "B.SilkS")
		)
		(fp_line
			(start 0.7874 0.4064)
			(end 0.7874 -0.4064)
			(stroke
				(width 0.1524)
				(type default)
			)
			(layer "B.SilkS")
		)
		(fp_line
			(start -0.67945 -0.3048)
			(end -0.67945 0.3048)
			(stroke
				(width 0.1)
				(type default)
			)
			(layer "B.Fab")
		)
		(fp_line
			(start -0.67945 0.3048)
			(end -0.120396 0.3048)
			(stroke
				(width 0.1)
				(type default)
			)
			(layer "B.Fab")
		)
		(fp_line
			(start -0.12065 -0.3048)
			(end -0.67945 -0.3048)
			(stroke
				(width 0.1)
				(type default)
			)
			(layer "B.Fab")
		)
		(fp_line
			(start -0.12065 -0.2794)
			(end -0.12065 -0.3048)
			(stroke
				(width 0.1)
				(type default)
			)
			(layer "B.Fab")
		)
		(fp_line
			(start -0.120396 0.2794)
			(end 0.12065 0.2794)
			(stroke
				(width 0.1)
				(type default)
			)
			(layer "B.Fab")
		)
		(fp_line
			(start -0.120396 0.3048)
			(end -0.120396 0.2794)
			(stroke
				(width 0.1)
				(type default)
			)
			(layer "B.Fab")
		)
		(fp_line
			(start 0.12065 -0.305054)
			(end 0.12065 -0.2794)
			(stroke
				(width 0.1)
				(type default)
			)
			(layer "B.Fab")
		)
		(fp_line
			(start 0.12065 -0.2794)
			(end -0.12065 -0.2794)
			(stroke
				(width 0.1)
				(type default)
			)
			(layer "B.Fab")
		)
		(fp_line
			(start 0.12065 0.2794)
			(end 0.12065 0.3048)
			(stroke
				(width 0.1)
				(type default)
			)
			(layer "B.Fab")
		)
		(fp_line
			(start 0.12065 0.3048)
			(end 0.67945 0.3048)
			(stroke
				(width 0.1)
				(type default)
			)
			(layer "B.Fab")
		)
		(fp_line
			(start 0.67945 -0.305054)
			(end 0.12065 -0.305054)
			(stroke
				(width 0.1)
				(type default)
			)
			(layer "B.Fab")
		)
		(fp_line
			(start 0.67945 0.3048)
			(end 0.67945 -0.305054)
			(stroke
				(width 0.1)
				(type default)
			)
			(layer "B.Fab")
		)
		(pad "1" smd circle
			(at 0.40005 0 180)
			(size 0 0)
			(layers "B.Cu" "B.Mask" "B.Paste")
			(net "PVDDCR_SOC_P0_EN_RC")
		)
		(pad "2" smd circle
			(at -0.40005 0 180)
			(size 0 0)
			(layers "B.Cu" "B.Mask" "B.Paste")
			(net "GND")
		)
	)
)
